(kicad_pcb
	(version 20260206)
	(generator "pcbnew")
	(generator_version "10.0")
	(general
		(thickness 1.6)
		(legacy_teardrops no)
	)
	(paper "A4")
	(title_block
		(title "12092022_DA0F0TMDCD0_F0T_Management_Board_D_brd_V3_OCP.brd")
		(comment 1 "Grand Teton / footprints 540-545 of 1440")
	)
	(layers
		(0 "F.Cu" signal "TOP")
		(4 "In1.Cu" signal "GND")
		(6 "In2.Cu" signal "IN1")
		(8 "In3.Cu" signal "GND1")
		(10 "In4.Cu" signal "IN2")
		(12 "In5.Cu" signal "VCC")
		(14 "In6.Cu" signal "VCC1")
		(16 "In7.Cu" signal "IN3")
		(18 "In8.Cu" signal "GND2")
		(20 "In9.Cu" signal "IN4")
		(22 "In10.Cu" signal "GND3")
		(2 "B.Cu" signal "BOTTOM")
		(9 "F.Adhes" user "F.Adhesive")
		(11 "B.Adhes" user "B.Adhesive")
		(13 "F.Paste" user "Package Geometry/Pastemask Top")
		(15 "B.Paste" user "Package Geometry/Pastemask Bottom")
		(5 "F.SilkS" user "Ref Des/Silkscreen Top")
		(7 "B.SilkS" user "Ref Des/Silkscreen Bottom")
		(1 "F.Mask" user "Board Geometry/Soldermask Top")
		(3 "B.Mask" user "Board Geometry/Soldermask Bottom")
		(17 "Dwgs.User" user "User.Drawings")
		(19 "Cmts.User" user "User.Comments")
		(21 "Eco1.User" user "User.Eco1")
		(23 "Eco2.User" user "User.Eco2")
		(25 "Edge.Cuts" user "Board Geometry/Outline")
		(27 "Margin" user)
		(31 "F.CrtYd" user "Package Geometry/Place Bound Top")
		(29 "B.CrtYd" user "Package Geometry/Place Bound Bottom")
		(35 "F.Fab" user "Ref Des/Assembly Top")
		(33 "B.Fab" user "Ref Des/Assembly Bottom")
	)
	(footprint ""
		(layer "F.Cu")
		(at 10.033 -88.519)
		(property "Reference" "R192"
			(at 0 0 0)
			(layer "F.SilkS")
			(hide yes)
			(effects
				(font
					(size 1.27 1.27)
				)
			)
		)
		(property "Value" ""
			(at 0 0 0)
			(layer "F.Fab")
			(effects
				(font
					(size 1.27 1.27)
				)
			)
		)
		(duplicate_pad_numbers_are_jumpers no)
		(fp_line
			(start -0.7874 -0.4064)
			(end 0.7874 -0.4064)
			(stroke
				(width 0.1524)
				(type default)
			)
			(layer "F.SilkS")
		)
		(fp_line
			(start -0.7874 0.4064)
			(end -0.7874 -0.4064)
			(stroke
				(width 0.1524)
				(type default)
			)
			(layer "F.SilkS")
		)
		(fp_line
			(start 0.7874 -0.4064)
			(end 0.7874 0.4064)
			(stroke
				(width 0.1524)
				(type default)
			)
			(layer "F.SilkS")
		)
		(fp_line
			(start 0.7874 0.4064)
			(end -0.7874 0.4064)
			(stroke
				(width 0.1524)
				(type default)
			)
			(layer "F.SilkS")
		)
		(fp_line
			(start -0.67945 -0.305054)
			(end -0.12065 -0.305054)
			(stroke
				(width 0.1)
				(type default)
			)
			(layer "F.Fab")
		)
		(fp_line
			(start -0.67945 0.3048)
			(end -0.67945 -0.305054)
			(stroke
				(width 0.1)
				(type default)
			)
			(layer "F.Fab")
		)
		(fp_line
			(start -0.12065 -0.305054)
			(end -0.12065 -0.2794)
			(stroke
				(width 0.1)
				(type default)
			)
			(layer "F.Fab")
		)
		(fp_line
			(start -0.12065 -0.2794)
			(end 0.12065 -0.2794)
			(stroke
				(width 0.1)
				(type default)
			)
			(layer "F.Fab")
		)
		(fp_line
			(start -0.12065 0.2794)
			(end -0.12065 0.3048)
			(stroke
				(width 0.1)
				(type default)
			)
			(layer "F.Fab")
		)
		(fp_line
			(start -0.12065 0.3048)
			(end -0.67945 0.3048)
			(stroke
				(width 0.1)
				(type default)
			)
			(layer "F.Fab")
		)
		(fp_line
			(start 0.120396 0.2794)
			(end -0.12065 0.2794)
			(stroke
				(width 0.1)
				(type default)
			)
			(layer "F.Fab")
		)
		(fp_line
			(start 0.120396 0.3048)
			(end 0.120396 0.2794)
			(stroke
				(width 0.1)
				(type default)
			)
			(layer "F.Fab")
		)
		(fp_line
			(start 0.12065 -0.3048)
			(end 0.67945 -0.3048)
			(stroke
				(width 0.1)
				(type default)
			)
			(layer "F.Fab")
		)
		(fp_line
			(start 0.12065 -0.2794)
			(end 0.12065 -0.3048)
			(stroke
				(width 0.1)
				(type default)
			)
			(layer "F.Fab")
		)
		(fp_line
			(start 0.67945 -0.3048)
			(end 0.67945 0.3048)
			(stroke
				(width 0.1)
				(type default)
			)
			(layer "F.Fab")
		)
		(fp_line
			(start 0.67945 0.3048)
			(end 0.120396 0.3048)
			(stroke
				(width 0.1)
				(type default)
			)
			(layer "F.Fab")
		)
		(pad "1" smd circle
			(at -0.40005 0)
			(size 0 0)
			(layers "F.Cu" "F.Mask" "F.Paste")
			(net "PWRGD_P1V0_AUX_DELAY_BUF")
		)
		(pad "2" smd circle
			(at 0.40005 0)
			(size 0 0)
			(layers "F.Cu" "F.Mask" "F.Paste")
			(net "RST_BMC_SRST_BUF_R_N")
		)
	)
	(footprint ""
		(layer "F.Cu")
		(at 39.871142 -63.756794 90)
		(property "Reference" "R200"
			(at 0 0 90)
			(layer "F.SilkS")
			(hide yes)
			(effects
				(font
					(size 1.27 1.27)
				)
			)
		)
		(property "Value" ""
			(at 0 0 90)
			(layer "F.Fab")
			(effects
				(font
					(size 1.27 1.27)
				)
			)
		)
		(duplicate_pad_numbers_are_jumpers no)
		(fp_line
			(start 0.7874 -0.4064)
			(end 0.7874 0.4064)
			(stroke
				(width 0.1524)
				(type default)
			)
			(layer "F.SilkS")
		)
		(fp_line
			(start -0.7874 -0.4064)
			(end 0.7874 -0.4064)
			(stroke
				(width 0.1524)
				(type default)
			)
			(layer "F.SilkS")
		)
		(fp_line
			(start 0.7874 0.4064)
			(end -0.7874 0.4064)
			(stroke
				(width 0.1524)
				(type default)
			)
			(layer "F.SilkS")
		)
		(fp_line
			(start -0.7874 0.4064)
			(end -0.7874 -0.4064)
			(stroke
				(width 0.1524)
				(type default)
			)
			(layer "F.SilkS")
		)
		(fp_line
			(start -0.12065 -0.305054)
			(end -0.12065 -0.2794)
			(stroke
				(width 0.1)
				(type default)
			)
			(layer "F.Fab")
		)
		(fp_line
			(start -0.67945 -0.305054)
			(end -0.12065 -0.305054)
			(stroke
				(width 0.1)
				(type default)
			)
			(layer "F.Fab")
		)
		(fp_line
			(start 0.67945 -0.3048)
			(end 0.67945 0.3048)
			(stroke
				(width 0.1)
				(type default)
			)
			(layer "F.Fab")
		)
		(fp_line
			(start 0.12065 -0.3048)
			(end 0.67945 -0.3048)
			(stroke
				(width 0.1)
				(type default)
			)
			(layer "F.Fab")
		)
		(fp_line
			(start 0.12065 -0.2794)
			(end 0.12065 -0.3048)
			(stroke
				(width 0.1)
				(type default)
			)
			(layer "F.Fab")
		)
		(fp_line
			(start -0.12065 -0.2794)
			(end 0.12065 -0.2794)
			(stroke
				(width 0.1)
				(type default)
			)
			(layer "F.Fab")
		)
		(fp_line
			(start 0.120396 0.2794)
			(end -0.12065 0.2794)
			(stroke
				(width 0.1)
				(type default)
			)
			(layer "F.Fab")
		)
		(fp_line
			(start -0.12065 0.2794)
			(end -0.12065 0.3048)
			(stroke
				(width 0.1)
				(type default)
			)
			(layer "F.Fab")
		)
		(fp_line
			(start 0.67945 0.3048)
			(end 0.120396 0.3048)
			(stroke
				(width 0.1)
				(type default)
			)
			(layer "F.Fab")
		)
		(fp_line
			(start 0.120396 0.3048)
			(end 0.120396 0.2794)
			(stroke
				(width 0.1)
				(type default)
			)
			(layer "F.Fab")
		)
		(fp_line
			(start -0.12065 0.3048)
			(end -0.67945 0.3048)
			(stroke
				(width 0.1)
				(type default)
			)
			(layer "F.Fab")
		)
		(fp_line
			(start -0.67945 0.3048)
			(end -0.67945 -0.305054)
			(stroke
				(width 0.1)
				(type default)
			)
			(layer "F.Fab")
		)
		(pad "1" smd circle
			(at -0.40005 0 90)
			(size 0 0)
			(layers "F.Cu" "F.Mask" "F.Paste")
			(net "I3C4_SCL_R")
		)
		(pad "2" smd circle
			(at 0.40005 0 90)
			(size 0 0)
			(layers "F.Cu" "F.Mask" "F.Paste")
			(net "I3C4_SPD_SCL")
		)
	)
	(footprint ""
		(layer "F.Cu")
		(at 62.53607 -34.870898 -90)
		(property "Reference" "R527"
			(at 0 0 270)
			(layer "F.SilkS")
			(hide yes)
			(effects
				(font
					(size 1.27 1.27)
				)
			)
		)
		(property "Value" ""
			(at 0 0 270)
			(layer "F.Fab")
			(effects
				(font
					(size 1.27 1.27)
				)
			)
		)
		(duplicate_pad_numbers_are_jumpers no)
		(fp_line
			(start -0.7874 0.4064)
			(end -0.7874 -0.14097)
			(stroke
				(width 0.1524)
				(type default)
			)
			(layer "F.SilkS")
		)
		(fp_line
			(start 0.7874 0.4064)
			(end -0.7874 0.4064)
			(stroke
				(width 0.1524)
				(type default)
			)
			(layer "F.SilkS")
		)
		(fp_line
			(start 0.7874 -0.04191)
			(end 0.7874 0.4064)
			(stroke
				(width 0.1524)
				(type default)
			)
			(layer "F.SilkS")
		)
		(fp_line
			(start -0.054102 -0.4064)
			(end 0.420878 -0.4064)
			(stroke
				(width 0.1524)
				(type default)
			)
			(layer "F.SilkS")
		)
		(fp_line
			(start -0.67945 0.3048)
			(end -0.67945 -0.305054)
			(stroke
				(width 0.1)
				(type default)
			)
			(layer "F.Fab")
		)
		(fp_line
			(start -0.12065 0.3048)
			(end -0.67945 0.3048)
			(stroke
				(width 0.1)
				(type default)
			)
			(layer "F.Fab")
		)
		(fp_line
			(start 0.120396 0.3048)
			(end 0.120396 0.2794)
			(stroke
				(width 0.1)
				(type default)
			)
			(layer "F.Fab")
		)
		(fp_line
			(start 0.67945 0.3048)
			(end 0.120396 0.3048)
			(stroke
				(width 0.1)
				(type default)
			)
			(layer "F.Fab")
		)
		(fp_line
			(start -0.12065 0.2794)
			(end -0.12065 0.3048)
			(stroke
				(width 0.1)
				(type default)
			)
			(layer "F.Fab")
		)
		(fp_line
			(start 0.120396 0.2794)
			(end -0.12065 0.2794)
			(stroke
				(width 0.1)
				(type default)
			)
			(layer "F.Fab")
		)
		(fp_line
			(start -0.12065 -0.2794)
			(end 0.12065 -0.2794)
			(stroke
				(width 0.1)
				(type default)
			)
			(layer "F.Fab")
		)
		(fp_line
			(start 0.12065 -0.2794)
			(end 0.12065 -0.3048)
			(stroke
				(width 0.1)
				(type default)
			)
			(layer "F.Fab")
		)
		(fp_line
			(start 0.12065 -0.3048)
			(end 0.67945 -0.3048)
			(stroke
				(width 0.1)
				(type default)
			)
			(layer "F.Fab")
		)
		(fp_line
			(start 0.67945 -0.3048)
			(end 0.67945 0.3048)
			(stroke
				(width 0.1)
				(type default)
			)
			(layer "F.Fab")
		)
		(fp_line
			(start -0.67945 -0.305054)
			(end -0.12065 -0.305054)
			(stroke
				(width 0.1)
				(type default)
			)
			(layer "F.Fab")
		)
		(fp_line
			(start -0.12065 -0.305054)
			(end -0.12065 -0.2794)
			(stroke
				(width 0.1)
				(type default)
			)
			(layer "F.Fab")
		)
		(pad "1" smd circle
			(at -0.40005 0 270)
			(size 0 0)
			(layers "F.Cu" "F.Mask" "F.Paste")
			(net "USB_HOST_BMC_B_R_DP")
		)
		(pad "2" smd circle
			(at 0.40005 0 270)
			(size 0 0)
			(layers "F.Cu" "F.Mask" "F.Paste")
			(net "USB_HOST_BMC_B_DP")
		)
	)
	(footprint ""
		(layer "F.Cu")
		(at 77.707744 -37.559488 -90)
		(property "Reference" "R355"
			(at 0 0 270)
			(layer "F.SilkS")
			(hide yes)
			(effects
				(font
					(size 1.27 1.27)
				)
			)
		)
		(property "Value" ""
			(at 0 0 270)
			(layer "F.Fab")
			(effects
				(font
					(size 1.27 1.27)
				)
			)
		)
		(duplicate_pad_numbers_are_jumpers no)
		(fp_line
			(start -0.7874 0.4064)
			(end -0.7874 -0.4064)
			(stroke
				(width 0.1524)
				(type default)
			)
			(layer "F.SilkS")
		)
		(fp_line
			(start 0.7874 0.4064)
			(end -0.7874 0.4064)
			(stroke
				(width 0.1524)
				(type default)
			)
			(layer "F.SilkS")
		)
		(fp_line
			(start -0.7874 -0.4064)
			(end 0.7874 -0.4064)
			(stroke
				(width 0.1524)
				(type default)
			)
			(layer "F.SilkS")
		)
		(fp_line
			(start 0.7874 -0.4064)
			(end 0.7874 0.4064)
			(stroke
				(width 0.1524)
				(type default)
			)
			(layer "F.SilkS")
		)
		(fp_line
			(start -0.67945 0.3048)
			(end -0.67945 -0.305054)
			(stroke
				(width 0.1)
				(type default)
			)
			(layer "F.Fab")
		)
		(fp_line
			(start -0.12065 0.3048)
			(end -0.67945 0.3048)
			(stroke
				(width 0.1)
				(type default)
			)
			(layer "F.Fab")
		)
		(fp_line
			(start 0.120396 0.3048)
			(end 0.120396 0.2794)
			(stroke
				(width 0.1)
				(type default)
			)
			(layer "F.Fab")
		)
		(fp_line
			(start 0.67945 0.3048)
			(end 0.120396 0.3048)
			(stroke
				(width 0.1)
				(type default)
			)
			(layer "F.Fab")
		)
		(fp_line
			(start -0.12065 0.2794)
			(end -0.12065 0.3048)
			(stroke
				(width 0.1)
				(type default)
			)
			(layer "F.Fab")
		)
		(fp_line
			(start 0.120396 0.2794)
			(end -0.12065 0.2794)
			(stroke
				(width 0.1)
				(type default)
			)
			(layer "F.Fab")
		)
		(fp_line
			(start -0.12065 -0.2794)
			(end 0.12065 -0.2794)
			(stroke
				(width 0.1)
				(type default)
			)
			(layer "F.Fab")
		)
		(fp_line
			(start 0.12065 -0.2794)
			(end 0.12065 -0.3048)
			(stroke
				(width 0.1)
				(type default)
			)
			(layer "F.Fab")
		)
		(fp_line
			(start 0.12065 -0.3048)
			(end 0.67945 -0.3048)
			(stroke
				(width 0.1)
				(type default)
			)
			(layer "F.Fab")
		)
		(fp_line
			(start 0.67945 -0.3048)
			(end 0.67945 0.3048)
			(stroke
				(width 0.1)
				(type default)
			)
			(layer "F.Fab")
		)
		(fp_line
			(start -0.67945 -0.305054)
			(end -0.12065 -0.305054)
			(stroke
				(width 0.1)
				(type default)
			)
			(layer "F.Fab")
		)
		(fp_line
			(start -0.12065 -0.305054)
			(end -0.12065 -0.2794)
			(stroke
				(width 0.1)
				(type default)
			)
			(layer "F.Fab")
		)
		(pad "1" smd circle
			(at -0.40005 0 270)
			(size 0 0)
			(layers "F.Cu" "F.Mask" "F.Paste")
			(net "M_BMC_DDR4_MA<4>")
		)
		(pad "2" smd circle
			(at 0.40005 0 270)
			(size 0 0)
			(layers "F.Cu" "F.Mask" "F.Paste")
			(net "P1V2_AUX")
		)
	)
	(footprint ""
		(layer "F.Cu")
		(at 32.999172 -83.816952 90)
		(property "Reference" "R532"
			(at 0 0 90)
			(layer "F.SilkS")
			(hide yes)
			(effects
				(font
					(size 1.27 1.27)
				)
			)
		)
		(property "Value" ""
			(at 0 0 90)
			(layer "F.Fab")
			(effects
				(font
					(size 1.27 1.27)
				)
			)
		)
		(duplicate_pad_numbers_are_jumpers no)
		(fp_line
			(start 0.7874 -0.4064)
			(end 0.7874 0.4064)
			(stroke
				(width 0.1524)
				(type default)
			)
			(layer "F.SilkS")
		)
		(fp_line
			(start -0.7874 -0.4064)
			(end 0.7874 -0.4064)
			(stroke
				(width 0.1524)
				(type default)
			)
			(layer "F.SilkS")
		)
		(fp_line
			(start 0.7874 0.4064)
			(end -0.7874 0.4064)
			(stroke
				(width 0.1524)
				(type default)
			)
			(layer "F.SilkS")
		)
		(fp_line
			(start -0.7874 0.4064)
			(end -0.7874 -0.4064)
			(stroke
				(width 0.1524)
				(type default)
			)
			(layer "F.SilkS")
		)
		(fp_line
			(start -0.12065 -0.305054)
			(end -0.12065 -0.2794)
			(stroke
				(width 0.1)
				(type default)
			)
			(layer "F.Fab")
		)
		(fp_line
			(start -0.67945 -0.305054)
			(end -0.12065 -0.305054)
			(stroke
				(width 0.1)
				(type default)
			)
			(layer "F.Fab")
		)
		(fp_line
			(start 0.67945 -0.3048)
			(end 0.67945 0.3048)
			(stroke
				(width 0.1)
				(type default)
			)
			(layer "F.Fab")
		)
		(fp_line
			(start 0.12065 -0.3048)
			(end 0.67945 -0.3048)
			(stroke
				(width 0.1)
				(type default)
			)
			(layer "F.Fab")
		)
		(fp_line
			(start 0.12065 -0.2794)
			(end 0.12065 -0.3048)
			(stroke
				(width 0.1)
				(type default)
			)
			(layer "F.Fab")
		)
		(fp_line
			(start -0.12065 -0.2794)
			(end 0.12065 -0.2794)
			(stroke
				(width 0.1)
				(type default)
			)
			(layer "F.Fab")
		)
		(fp_line
			(start 0.120396 0.2794)
			(end -0.12065 0.2794)
			(stroke
				(width 0.1)
				(type default)
			)
			(layer "F.Fab")
		)
		(fp_line
			(start -0.12065 0.2794)
			(end -0.12065 0.3048)
			(stroke
				(width 0.1)
				(type default)
			)
			(layer "F.Fab")
		)
		(fp_line
			(start 0.67945 0.3048)
			(end 0.120396 0.3048)
			(stroke
				(width 0.1)
				(type default)
			)
			(layer "F.Fab")
		)
		(fp_line
			(start 0.120396 0.3048)
			(end 0.120396 0.2794)
			(stroke
				(width 0.1)
				(type default)
			)
			(layer "F.Fab")
		)
		(fp_line
			(start -0.12065 0.3048)
			(end -0.67945 0.3048)
			(stroke
				(width 0.1)
				(type default)
			)
			(layer "F.Fab")
		)
		(fp_line
			(start -0.67945 0.3048)
			(end -0.67945 -0.305054)
			(stroke
				(width 0.1)
				(type default)
			)
			(layer "F.Fab")
		)
		(pad "1" smd circle
			(at -0.40005 0 90)
			(size 0 0)
			(layers "F.Cu" "F.Mask" "F.Paste")
			(net "EMMC_DT3_R")
		)
		(pad "2" smd circle
			(at 0.40005 0 90)
			(size 0 0)
			(layers "F.Cu" "F.Mask" "F.Paste")
			(net "BMC_EMMC_DT3")
		)
	)
	(footprint ""
		(layer "F.Cu")
		(at 37.5666 -88.9254 -90)
		(property "Reference" "C246"
			(at 0 0 270)
			(layer "F.SilkS")
			(hide yes)
			(effects
				(font
					(size 1.27 1.27)
				)
			)
		)
		(property "Value" ""
			(at 0 0 270)
			(layer "F.Fab")
			(effects
				(font
					(size 1.27 1.27)
				)
			)
		)
		(duplicate_pad_numbers_are_jumpers no)
		(fp_line
			(start -0.7874 0.4064)
			(end -0.7874 -0.4064)
			(stroke
				(width 0.1524)
				(type default)
			)
			(layer "F.SilkS")
		)
		(fp_line
			(start 0.7874 0.4064)
			(end -0.7874 0.4064)
			(stroke
				(width 0.1524)
				(type default)
			)
			(layer "F.SilkS")
		)
		(fp_line
			(start -0.7874 -0.4064)
			(end 0.7874 -0.4064)
			(stroke
				(width 0.1524)
				(type default)
			)
			(layer "F.SilkS")
		)
		(fp_line
			(start 0.7874 -0.4064)
			(end 0.7874 0.4064)
			(stroke
				(width 0.1524)
				(type default)
			)
			(layer "F.SilkS")
		)
		(fp_line
			(start -0.67945 0.3048)
			(end -0.67945 -0.305054)
			(stroke
				(width 0.1)
				(type default)
			)
			(layer "F.Fab")
		)
		(fp_line
			(start -0.12065 0.3048)
			(end -0.67945 0.3048)
			(stroke
				(width 0.1)
				(type default)
			)
			(layer "F.Fab")
		)
		(fp_line
			(start 0.120396 0.3048)
			(end 0.120396 0.2794)
			(stroke
				(width 0.1)
				(type default)
			)
			(layer "F.Fab")
		)
		(fp_line
			(start 0.67945 0.3048)
			(end 0.120396 0.3048)
			(stroke
				(width 0.1)
				(type default)
			)
			(layer "F.Fab")
		)
		(fp_line
			(start -0.12065 0.2794)
			(end -0.12065 0.3048)
			(stroke
				(width 0.1)
				(type default)
			)
			(layer "F.Fab")
		)
		(fp_line
			(start 0.120396 0.2794)
			(end -0.12065 0.2794)
			(stroke
				(width 0.1)
				(type default)
			)
			(layer "F.Fab")
		)
		(fp_line
			(start -0.12065 -0.2794)
			(end 0.12065 -0.2794)
			(stroke
				(width 0.1)
				(type default)
			)
			(layer "F.Fab")
		)
		(fp_line
			(start 0.12065 -0.2794)
			(end 0.12065 -0.3048)
			(stroke
				(width 0.1)
				(type default)
			)
			(layer "F.Fab")
		)
		(fp_line
			(start 0.12065 -0.3048)
			(end 0.67945 -0.3048)
			(stroke
				(width 0.1)
				(type default)
			)
			(layer "F.Fab")
		)
		(fp_line
			(start 0.67945 -0.3048)
			(end 0.67945 0.3048)
			(stroke
				(width 0.1)
				(type default)
			)
			(layer "F.Fab")
		)
		(fp_line
			(start -0.67945 -0.305054)
			(end -0.12065 -0.305054)
			(stroke
				(width 0.1)
				(type default)
			)
			(layer "F.Fab")
		)
		(fp_line
			(start -0.12065 -0.305054)
			(end -0.12065 -0.2794)
			(stroke
				(width 0.1)
				(type default)
			)
			(layer "F.Fab")
		)
		(pad "1" smd circle
			(at -0.40005 0 270)
			(size 0 0)
			(layers "F.Cu" "F.Mask" "F.Paste")
			(net "P3V3_AUX")
		)
		(pad "2" smd circle
			(at 0.40005 0 270)
			(size 0 0)
			(layers "F.Cu" "F.Mask" "F.Paste")
			(net "GND")
		)
	)
)
